# S9S_MB_2U (Grand Teton) — schematic netlist excerpt (pin names and nets, part order shuffled) for the footprints in the layout excerpt that follows; sources: Cadence DE-HDL packaged netlist, KiCad conversion of 03242023_DA0F0TMBIJ0_F0T_Motherboard_J_brd_V01_OCP.brd

J3  SCONN288_ADR50017P130CC  SCONN288_ADR50017-P130CC IO  pkg DDR288S_1-1VXB  page 84
  VIN_BULK0  = P12V_S3_AUX_CPU0_NVDIMM
  RFU0  = TP_CHB_CPU0_DIMM1_FRU_0
  VIN_MGMT  = P3V3_AUX
  HSCL  = I3C_SPD_DDRABCD_CPU0_LVC1_SCL_2
  HSDA  = I3C_SPD_DDRABCD_CPU0_LVC1_SDA
  VSS0  = GND
  DQ0_A  = M_B_CPU0_SA_DQ<0>
  VSS1  = GND
  DQ1_A  = M_B_CPU0_SA_DQ<1>
  VSS2  = GND
  DQS0_A_T  = M_B_CPU0_SA_DQS_DP<0>
  DQS0_A_C  = M_B_CPU0_SA_DQS_DN<0>
  VSS3  = GND
  DQ4_A  = M_B_CPU0_SA_DQ<4>
  VSS4  = GND
  DQ5_A  = M_B_CPU0_SA_DQ<5>
  VSS5  = GND
  DQ8_A  = M_B_CPU0_SA_DQ<8>
  VSS6  = GND
  DQ9_A  = M_B_CPU0_SA_DQ<9>
  VSS7  = GND
  DQS1_A_T  = M_B_CPU0_SA_DQS_DP<1>
  DQS1_A_C  = M_B_CPU0_SA_DQS_DN<1>
  VSS8  = GND
  DQ12_A  = M_B_CPU0_SA_DQ<12>
  VSS9  = GND
  DQ13_A  = M_B_CPU0_SA_DQ<13>
  VSS10  = GND
  DQ16_A  = M_B_CPU0_SA_DQ<16>
  VSS11  = GND
  DQ17_A  = M_B_CPU0_SA_DQ<17>
  VSS12  = GND
  DQS2_A_T  = M_B_CPU0_SA_DQS_DP<2>
  DQS2_A_C  = M_B_CPU0_SA_DQS_DN<2>
  VSS13  = GND
  DQ20_A  = M_B_CPU0_SA_DQ<20>
  VSS14  = GND
  DQ21_A  = M_B_CPU0_SA_DQ<21>
  VSS15  = GND
  DQ24_A  = M_B_CPU0_SA_DQ<24>
  VSS16  = GND
  DQ25_A  = M_B_CPU0_SA_DQ<25>
  VSS17  = GND
  DQS3_A_T  = M_B_CPU0_SA_DQS_DP<3>
  DQS3_A_C  = M_B_CPU0_SA_DQS_DN<3>
  VSS18  = GND
  DQ28_A  = M_B_CPU0_SA_DQ<28>
  VSS19  = GND
  DQ29_A  = M_B_CPU0_SA_DQ<29>
  VSS20  = GND
  CB0_A  = M_B_CPU0_SA_CB<0>
  VSS21  = GND
  CB1_A  = M_B_CPU0_SA_CB<1>
  VSS22  = GND
  DQS4_A_T  = M_B_CPU0_SA_DQS_DP<4>
  DQS4_A_C  = M_B_CPU0_SA_DQS_DN<4>
  VSS23  = GND
  CB4_A  = M_B_CPU0_SA_CB<4>
  VSS24  = GND
  CB5_A  = M_B_CPU0_SA_CB<5>
  VSS25  = GND
  ALERT_N  = M_B_CPU0_ALERT_N
  VSS26  = GND
  CS0_A_N  = M_B_CPU0_SA_CS_N<0>
  VSS27  = GND
  CA0_A  = M_B_CPU0_SA_CA<0>
  VSS28  = GND
  CA2_A  = M_B_CPU0_SA_CA<2>
  VSS29  = GND
  CA4_A  = M_B_CPU0_SA_CA<4>
  VSS30  = GND
  CA6_A  = M_B_CPU0_SA_CA<6>
  VSS31  = GND
  PAR_A  = M_B_CPU0_SA_PAR
  VSS32  = GND
  CA0_B  = M_B_CPU0_SB_CA<0>
  VSS33  = GND
  CA2_B  = M_B_CPU0_SB_CA<2>
  VSS34  = GND
  CA4_B  = M_B_CPU0_SB_CA<4>
  VSS35  = GND
  CA6_B  = M_B_CPU0_SB_CA<6>
  VSS36  = GND
  CS0_B_N  = M_B_CPU0_SB_CS_N<0>
  VSS37  = GND
  \lbd||rsp_a_n\  = M_B_CPU0_SA_RSP<0>
  \lbs||rsp_b_n\  = M_B_CPU0_SB_RSP<0>
  VSS38  = GND
  CB4_B  = M_B_CPU0_SB_CB<4>
  VSS39  = GND
  CB5_B  = M_B_CPU0_SB_CB<5>
  VSS40  = GND
  \dqs9_b_t||tdqs9_b_t||dbi4_b_n\  = M_B_CPU0_SB_DQS_DP<9>
  \dqs9_b_c||tdqs9_b_c\  = M_B_CPU0_SB_DQS_DN<9>
  VSS41  = GND
  CB0_B  = M_B_CPU0_SB_CB<0>
  VSS42  = GND
  CB1_B  = M_B_CPU0_SB_CB<1>
  VSS43  = GND
  DQ0_B  = M_B_CPU0_SB_DQ<0>
  VSS44  = GND
  DQ1_B  = M_B_CPU0_SB_DQ<1>
  VSS45  = GND
  DQS0_B_T  = M_B_CPU0_SB_DQS_DP<0>
  DQS0_B_C  = M_B_CPU0_SB_DQS_DN<0>
  VSS46  = GND
  DQ4_B  = M_B_CPU0_SB_DQ<4>
  VSS47  = GND
  DQ5_B  = M_B_CPU0_SB_DQ<5>
  VSS48  = GND
  DQ8_B  = M_B_CPU0_SB_DQ<8>
  VSS49  = GND
  DQ9_B  = M_B_CPU0_SB_DQ<9>
  VSS50  = GND
  DQS1_B_T  = M_B_CPU0_SB_DQS_DP<1>
  DQS1_B_C  = M_B_CPU0_SB_DQS_DN<1>
  VSS51  = GND
  DQ12_B  = M_B_CPU0_SB_DQ<12>
  VSS52  = GND
  DQ13_B  = M_B_CPU0_SB_DQ<13>
  VSS53  = GND
  DQ16_B  = M_B_CPU0_SB_DQ<16>
  VSS54  = GND
  DQ17_B  = M_B_CPU0_SB_DQ<17>
  VSS55  = GND
  DQS2_B_T  = M_B_CPU0_SB_DQS_DP<2>
  DQS2_B_C  = M_B_CPU0_SB_DQS_DN<2>
  VSS56  = GND
  DQ20_B  = M_B_CPU0_SB_DQ<20>
  VSS57  = GND
  DQ21_B  = M_B_CPU0_SB_DQ<21>
  VSS58  = GND
  DQ24_B  = M_B_CPU0_SB_DQ<24>
  VSS59  = GND
  DQ25_B  = M_B_CPU0_SB_DQ<25>
  VSS60  = GND
  DQS3_B_T  = M_B_CPU0_SB_DQS_DP<3>
  DQS3_B_C  = M_B_CPU0_SB_DQS_DN<3>
  VSS61  = GND
  DQ28_B  = M_B_CPU0_SB_DQ<28>
  VSS62  = GND
  DQ29_B  = M_B_CPU0_SB_DQ<29>
  VSS63  = GND
  RFU1  = TP_CHB_CPU0_DIMM1_FRU_1
  VIN_BULK1  = P12V_S3_AUX_CPU0_NVDIMM
  VIN_BULK2  = P12V_S3_AUX_CPU0_NVDIMM
  \pwr_good||fail_n\  = PWRGD_CHB_CPU0_DIMM1
  HSA  = PD_CHB_CPU0_DIMM1_SAA
  RFU2  = TP_CHB_CPU0_DIMM1_FRU_2
  RFU3  = TP_CHB_CPU0_DIMM1_FRU_3
  VSS64  = GND
  DQ2_A  = M_B_CPU0_SA_DQ<2>
  VSS65  = GND
  DQ3_A  = M_B_CPU0_SA_DQ<3>
  VSS66  = GND
  \dqs5_a_c||tdqs5_a_c||dqs5_a_t||tdqs5_a_t\  = M_B_CPU0_SA_DQS_DN<5>
  \dqs5_a_t||tdqs5_a_t\  = M_B_CPU0_SA_DQS_DP<5>
  VSS67  = GND
  DQ6_A  = M_B_CPU0_SA_DQ<6>
  VSS68  = GND
  DQ7_A  = M_B_CPU0_SA_DQ<7>
  VSS69  = GND
  DQ10_A  = M_B_CPU0_SA_DQ<10>
  VSS70  = GND
  DQ11_A  = M_B_CPU0_SA_DQ<11>
  VSS71  = GND
  \dqs6_a_c||tdqs6_a_c||dqs6_a_t||tdqs6_a_t\  = M_B_CPU0_SA_DQS_DN<6>
  \dqs6_a_t||tdqs6_a_t\  = M_B_CPU0_SA_DQS_DP<6>
  VSS72  = GND
  DQ14_A  = M_B_CPU0_SA_DQ<14>
  VSS73  = GND
  DQ15_A  = M_B_CPU0_SA_DQ<15>
  VSS74  = GND
  DQ18_A  = M_B_CPU0_SA_DQ<18>
  VSS75  = GND
  DQ19_A  = M_B_CPU0_SA_DQ<19>
  VSS76  = GND
  \dqs7_a_c||tdqs7_a_c\  = M_B_CPU0_SA_DQS_DN<7>
  \dqs7_a_t||tdqs7_a_t\  = M_B_CPU0_SA_DQS_DP<7>
  VSS77  = GND
  DQ22_A  = M_B_CPU0_SA_DQ<22>
  VSS78  = GND
  DQ23_A  = M_B_CPU0_SA_DQ<23>
  VSS79  = GND
  DQ26_A  = M_B_CPU0_SA_DQ<26>
  VSS80  = GND
  DQ27_A  = M_B_CPU0_SA_DQ<27>
  VSS81  = GND
  \dqs8_a_c||tdqs8_a_c\  = M_B_CPU0_SA_DQS_DN<8>
  \dqs8_a_t||tdqs8_a_t\  = M_B_CPU0_SA_DQS_DP<8>
  VSS82  = GND
  DQ30_A  = M_B_CPU0_SA_DQ<30>
  VSS83  = GND
  DQ31_A  = M_B_CPU0_SA_DQ<31>
  VSS84  = GND
  CB2_A  = M_B_CPU0_SA_CB<2>
  VSS85  = GND
  CB3_A  = M_B_CPU0_SA_CB<3>
  VSS86  = GND
  \dqs9_a_c||tdqs9_a_c\  = M_B_CPU0_SA_DQS_DN<9>
  \dqs9_a_t||tdqs9_a_t\  = M_B_CPU0_SA_DQS_DP<9>
  VSS87  = GND
  CB6_A  = M_B_CPU0_SA_CB<6>
  VSS88  = GND
  CB7_A  = M_B_CPU0_SA_CB<7>
  VSS89  = GND
  RESET_N  = RST_M_AB_CPU0_FPGA_N
  VSS90  = GND
  CS1_A_N  = M_B_CPU0_SA_CS_N<1>
  VSS91  = GND
  CA1_A  = M_B_CPU0_SA_CA<1>
  VSS92  = GND
  CA3_A  = M_B_CPU0_SA_CA<3>
  VSS93  = GND
  CA5_A  = M_B_CPU0_SA_CA<5>
  VSS94  = GND
  CK_T  = M_B_CPU0_CLK_DP<0>
  CK_C  = M_B_CPU0_CLK_DN<0>
  VSS95  = GND
  RFU4  = TP_CHB_CPU0_DIMM1_FRU_4
  CA1_B  = M_B_CPU0_SB_CA<1>
  VSS96  = GND
  CA3_B  = M_B_CPU0_SB_CA<3>
  VSS97  = GND
  CA5_B  = M_B_CPU0_SB_CA<5>
  VSS98  = GND
  PAR_B  = M_B_CPU0_SB_PAR
  VSS99  = GND
  CS1_B_N  = M_B_CPU0_SB_CS_N<1>
  VSS100  = GND
  RFU5  = TP_CHB_CPU0_DIMM1_FRU_5
  RFU6  = TP_CHB_CPU0_DIMM1_FRU_6
  VSS101  = GND
  CB6_B  = M_B_CPU0_SB_CB<6>
  VSS102  = GND
  CB7_B  = M_B_CPU0_SB_CB<7>
  VSS103  = GND
  DQS4_B_C  = M_B_CPU0_SB_DQS_DN<4>
  DQS4_B_T  = M_B_CPU0_SB_DQS_DP<4>
  VSS104  = GND
  CB2_B  = M_B_CPU0_SB_CB<2>
  VSS105  = GND
  CB3_B  = M_B_CPU0_SB_CB<3>
  VSS106  = GND
  DQ2_B  = M_B_CPU0_SB_DQ<2>
  VSS107  = GND
  DQ3_B  = M_B_CPU0_SB_DQ<3>
  VSS108  = GND
  \dqs5_b_c||tdqs5_b_c\  = M_B_CPU0_SB_DQS_DN<5>
  \dqs5_b_t||tdqs5_b_t\  = M_B_CPU0_SB_DQS_DP<5>
  VSS109  = GND
  DQ6_B  = M_B_CPU0_SB_DQ<6>
  VSS110  = GND
  DQ7_B  = M_B_CPU0_SB_DQ<7>
  VSS111  = GND
  DQ10_B  = M_B_CPU0_SB_DQ<10>
  VSS112  = GND
  DQ11_B  = M_B_CPU0_SB_DQ<11>
  VSS113  = GND
  \dqs6_b_c||tdqs6_b_c\  = M_B_CPU0_SB_DQS_DN<6>
  \dqs6_b_t||tdqs6_b_t\  = M_B_CPU0_SB_DQS_DP<6>
  VSS114  = GND
  DQ14_B  = M_B_CPU0_SB_DQ<14>
  VSS115  = GND
  DQ15_B  = M_B_CPU0_SB_DQ<15>
  VSS116  = GND
  DQ18_B  = M_B_CPU0_SB_DQ<18>
  VSS117  = GND
  DQ19_B  = M_B_CPU0_SB_DQ<19>
  VSS118  = GND
  \dqs7_b_c||tdqs7_b_c\  = M_B_CPU0_SB_DQS_DN<7>
  \dqs7_b_t||tdqs7_b_t\  = M_B_CPU0_SB_DQS_DP<7>
  VSS119  = GND
  DQ22_B  = M_B_CPU0_SB_DQ<22>
  VSS120  = GND
  DQ23_B  = M_B_CPU0_SB_DQ<23>
  VSS121  = GND
  DQ26_B  = M_B_CPU0_SB_DQ<26>
  VSS122  = GND
  DQ27_B  = M_B_CPU0_SB_DQ<27>
  VSS123  = GND
  \dqs8_b_c||tdqs8_b_c\  = M_B_CPU0_SB_DQS_DN<8>
  \dqs8_b_t||tdqs8_b_t\  = M_B_CPU0_SB_DQS_DP<8>
  VSS124  = GND
  DQ30_B  = M_B_CPU0_SB_DQ<30>
  VSS125  = GND
  DQ31_B  = M_B_CPU0_SB_DQ<31>
  VSS126  = GND
  G1  = GND
  G2  = GND
  G3  = GND

(kicad_pcb
	(version 20260206)
	(generator "pcbnew")
	(generator_version "10.0")
	(general
		(thickness 1.6)
		(legacy_teardrops no)
	)
	(paper "A4")
	(title_block
		(title "03242023_DA0F0TMBIJ0_F0T_Motherboard_J_brd_V01_OCP.brd")
		(comment 1 "Grand Teton / footprint 2048 of 6105 (J3), pads 229-274 of 291")
	)
	(layers
		(0 "F.Cu" signal "TOP")
		(4 "In1.Cu" signal "GND")
		(6 "In2.Cu" signal "IN1")
		(8 "In3.Cu" signal "GND1")
		(10 "In4.Cu" signal "IN2")
		(12 "In5.Cu" signal "GND2")
		(14 "In6.Cu" signal "IN3")
		(16 "In7.Cu" signal "GND3")
		(18 "In8.Cu" signal "VCC")
		(20 "In9.Cu" signal "VCC1")
		(22 "In10.Cu" signal "GND4")
		(24 "In11.Cu" signal "IN4")
		(26 "In12.Cu" signal "GND5")
		(28 "In13.Cu" signal "IN5")
		(30 "In14.Cu" signal "GND6")
		(32 "In15.Cu" signal "IN6")
		(34 "In16.Cu" signal "GND7")
		(2 "B.Cu" signal "BOTTOM")
		(9 "F.Adhes" user "F.Adhesive")
		(11 "B.Adhes" user "B.Adhesive")
		(13 "F.Paste" user "Package Geometry/Pastemask Top")
		(15 "B.Paste" user "Package Geometry/Pastemask Bottom")
		(5 "F.SilkS" user "Ref Des/Silkscreen Top")
		(7 "B.SilkS" user "Ref Des/Silkscreen Bottom")
		(1 "F.Mask" user "Board Geometry/Soldermask Top")
		(3 "B.Mask" user "Board Geometry/Soldermask Bottom")
		(17 "Dwgs.User" user "User.Drawings")
		(19 "Cmts.User" user "User.Comments")
		(21 "Eco1.User" user "User.Eco1")
		(23 "Eco2.User" user "User.Eco2")
		(25 "Edge.Cuts" user "Board Geometry/Outline")
		(27 "Margin" user)
		(31 "F.CrtYd" user "Package Geometry/Place Bound Top")
		(29 "B.CrtYd" user "Package Geometry/Place Bound Bottom")
		(35 "F.Fab" user "Ref Des/Assembly Top")
		(33 "B.Fab" user "Ref Des/Assembly Bottom")
	)
	(footprint ""
		(layer "F.Cu")
		(at 288.305748 -258.091686)
		(property "Reference" "J3"
			(at -3.683 -81.702148 0)
			(unlocked yes)
			(layer "F.SilkS")
			(effects
				(font
					(size 0.7874 0.5842)
					(thickness 0.1524)
				)
				(justify left)
			)
		)
		(property "Value" ""
			(at 0 0 0)
			(layer "F.Fab")
			(effects
				(font
					(size 1.27 1.27)
				)
			)
		)
		(duplicate_pad_numbers_are_jumpers no)
		(pad "229" smd rect
			(at 2.050034 13.17498 270)
			(size 0.519938 1.4986)
			(layers "F.Cu" "F.Mask" "F.Paste")
			(net "M_B_CPU0_SB_CS_N<1>")
		)
		(pad "230" smd rect
			(at 2.050034 14.025118 270)
			(size 0.519938 1.4986)
			(layers "F.Cu" "F.Mask" "F.Paste")
			(net "GND")
		)
		(pad "231" smd rect
			(at 2.050034 14.875002 270)
			(size 0.519938 1.4986)
			(layers "F.Cu" "F.Mask" "F.Paste")
			(net "TP_CHB_CPU0_DIMM1_FRU_5")
		)
		(pad "232" smd rect
			(at 2.050034 15.724886 270)
			(size 0.519938 1.4986)
			(layers "F.Cu" "F.Mask" "F.Paste")
			(net "TP_CHB_CPU0_DIMM1_FRU_6")
		)
		(pad "233" smd rect
			(at 2.050034 16.575024 270)
			(size 0.519938 1.4986)
			(layers "F.Cu" "F.Mask" "F.Paste")
			(net "GND")
		)
		(pad "234" smd rect
			(at 2.050034 17.424908 270)
			(size 0.519938 1.4986)
			(layers "F.Cu" "F.Mask" "F.Paste")
			(net "M_B_CPU0_SB_CB<6>")
		)
		(pad "235" smd rect
			(at 2.050034 18.275046 270)
			(size 0.519938 1.4986)
			(layers "F.Cu" "F.Mask" "F.Paste")
			(net "GND")
		)
		(pad "236" smd rect
			(at 2.050034 19.12493 270)
			(size 0.519938 1.4986)
			(layers "F.Cu" "F.Mask" "F.Paste")
			(net "M_B_CPU0_SB_CB<7>")
		)
		(pad "237" smd rect
			(at 2.050034 19.975068 270)
			(size 0.519938 1.4986)
			(layers "F.Cu" "F.Mask" "F.Paste")
			(net "GND")
		)
		(pad "238" smd rect
			(at 2.050034 20.824952 270)
			(size 0.519938 1.4986)
			(layers "F.Cu" "F.Mask" "F.Paste")
			(net "M_B_CPU0_SB_DQS_DN<4>")
		)
		(pad "239" smd rect
			(at 2.050034 21.67509 270)
			(size 0.519938 1.4986)
			(layers "F.Cu" "F.Mask" "F.Paste")
			(net "M_B_CPU0_SB_DQS_DP<4>")
		)
		(pad "240" smd rect
			(at 2.050034 22.524974 270)
			(size 0.519938 1.4986)
			(layers "F.Cu" "F.Mask" "F.Paste")
			(net "GND")
		)
		(pad "241" smd rect
			(at 2.050034 23.375112 270)
			(size 0.519938 1.4986)
			(layers "F.Cu" "F.Mask" "F.Paste")
			(net "M_B_CPU0_SB_CB<2>")
		)
		(pad "242" smd rect
			(at 2.050034 24.224996 270)
			(size 0.519938 1.4986)
			(layers "F.Cu" "F.Mask" "F.Paste")
			(net "GND")
		)
		(pad "243" smd rect
			(at 2.050034 25.07488 270)
			(size 0.519938 1.4986)
			(layers "F.Cu" "F.Mask" "F.Paste")
			(net "M_B_CPU0_SB_CB<3>")
		)
		(pad "244" smd rect
			(at 2.050034 25.925018 270)
			(size 0.519938 1.4986)
			(layers "F.Cu" "F.Mask" "F.Paste")
			(net "GND")
		)
		(pad "245" smd rect
			(at 2.050034 26.774902 270)
			(size 0.519938 1.4986)
			(layers "F.Cu" "F.Mask" "F.Paste")
			(net "M_B_CPU0_SB_DQ<2>")
		)
		(pad "246" smd rect
			(at 2.050034 27.62504 270)
			(size 0.519938 1.4986)
			(layers "F.Cu" "F.Mask" "F.Paste")
			(net "GND")
		)
		(pad "247" smd rect
			(at 2.050034 28.474924 270)
			(size 0.519938 1.4986)
			(layers "F.Cu" "F.Mask" "F.Paste")
			(net "M_B_CPU0_SB_DQ<3>")
		)
		(pad "248" smd rect
			(at 2.050034 29.325062 270)
			(size 0.519938 1.4986)
			(layers "F.Cu" "F.Mask" "F.Paste")
			(net "GND")
		)
		(pad "249" smd rect
			(at 2.050034 30.174946 270)
			(size 0.519938 1.4986)
			(layers "F.Cu" "F.Mask" "F.Paste")
			(net "M_B_CPU0_SB_DQS_DN<5>")
		)
		(pad "250" smd rect
			(at 2.050034 31.025084 270)
			(size 0.519938 1.4986)
			(layers "F.Cu" "F.Mask" "F.Paste")
			(net "M_B_CPU0_SB_DQS_DP<5>")
		)
		(pad "251" smd rect
			(at 2.050034 31.874968 270)
			(size 0.519938 1.4986)
			(layers "F.Cu" "F.Mask" "F.Paste")
			(net "GND")
		)
		(pad "252" smd rect
			(at 2.050034 32.725106 270)
			(size 0.519938 1.4986)
			(layers "F.Cu" "F.Mask" "F.Paste")
			(net "M_B_CPU0_SB_DQ<6>")
		)
		(pad "253" smd rect
			(at 2.050034 33.57499 270)
			(size 0.519938 1.4986)
			(layers "F.Cu" "F.Mask" "F.Paste")
			(net "GND")
		)
		(pad "254" smd rect
			(at 2.050034 34.425128 270)
			(size 0.519938 1.4986)
			(layers "F.Cu" "F.Mask" "F.Paste")
			(net "M_B_CPU0_SB_DQ<7>")
		)
		(pad "255" smd rect
			(at 2.050034 35.275012 270)
			(size 0.519938 1.4986)
			(layers "F.Cu" "F.Mask" "F.Paste")
			(net "GND")
		)
		(pad "256" smd rect
			(at 2.050034 36.124896 270)
			(size 0.519938 1.4986)
			(layers "F.Cu" "F.Mask" "F.Paste")
			(net "M_B_CPU0_SB_DQ<10>")
		)
		(pad "257" smd rect
			(at 2.050034 36.975034 270)
			(size 0.519938 1.4986)
			(layers "F.Cu" "F.Mask" "F.Paste")
			(net "GND")
		)
		(pad "258" smd rect
			(at 2.050034 37.824918 270)
			(size 0.519938 1.4986)
			(layers "F.Cu" "F.Mask" "F.Paste")
			(net "M_B_CPU0_SB_DQ<11>")
		)
		(pad "259" smd rect
			(at 2.050034 38.675056 270)
			(size 0.519938 1.4986)
			(layers "F.Cu" "F.Mask" "F.Paste")
			(net "GND")
		)
		(pad "260" smd rect
			(at 2.050034 39.52494 270)
			(size 0.519938 1.4986)
			(layers "F.Cu" "F.Mask" "F.Paste")
			(net "M_B_CPU0_SB_DQS_DN<6>")
		)
		(pad "261" smd rect
			(at 2.050034 40.375078 270)
			(size 0.519938 1.4986)
			(layers "F.Cu" "F.Mask" "F.Paste")
			(net "M_B_CPU0_SB_DQS_DP<6>")
		)
		(pad "262" smd rect
			(at 2.050034 41.224962 270)
			(size 0.519938 1.4986)
			(layers "F.Cu" "F.Mask" "F.Paste")
			(net "GND")
		)
		(pad "263" smd rect
			(at 2.050034 42.0751 270)
			(size 0.519938 1.4986)
			(layers "F.Cu" "F.Mask" "F.Paste")
			(net "M_B_CPU0_SB_DQ<14>")
		)
		(pad "264" smd rect
			(at 2.050034 42.924984 270)
			(size 0.519938 1.4986)
			(layers "F.Cu" "F.Mask" "F.Paste")
			(net "GND")
		)
		(pad "265" smd rect
			(at 2.050034 43.775122 270)
			(size 0.519938 1.4986)
			(layers "F.Cu" "F.Mask" "F.Paste")
			(net "M_B_CPU0_SB_DQ<15>")
		)
		(pad "266" smd rect
			(at 2.050034 44.625006 270)
			(size 0.519938 1.4986)
			(layers "F.Cu" "F.Mask" "F.Paste")
			(net "GND")
		)
		(pad "267" smd rect
			(at 2.050034 45.47489 270)
			(size 0.519938 1.4986)
			(layers "F.Cu" "F.Mask" "F.Paste")
			(net "M_B_CPU0_SB_DQ<18>")
		)
		(pad "268" smd rect
			(at 2.050034 46.325028 270)
			(size 0.519938 1.4986)
			(layers "F.Cu" "F.Mask" "F.Paste")
			(net "GND")
		)
		(pad "269" smd rect
			(at 2.050034 47.174912 270)
			(size 0.519938 1.4986)
			(layers "F.Cu" "F.Mask" "F.Paste")
			(net "M_B_CPU0_SB_DQ<19>")
		)
		(pad "270" smd rect
			(at 2.050034 48.02505 270)
			(size 0.519938 1.4986)
			(layers "F.Cu" "F.Mask" "F.Paste")
			(net "GND")
		)
		(pad "271" smd rect
			(at 2.050034 48.874934 270)
			(size 0.519938 1.4986)
			(layers "F.Cu" "F.Mask" "F.Paste")
			(net "M_B_CPU0_SB_DQS_DN<7>")
		)
		(pad "272" smd rect
			(at 2.050034 49.725072 270)
			(size 0.519938 1.4986)
			(layers "F.Cu" "F.Mask" "F.Paste")
			(net "M_B_CPU0_SB_DQS_DP<7>")
		)
		(pad "273" smd rect
			(at 2.050034 50.574956 270)
			(size 0.519938 1.4986)
			(layers "F.Cu" "F.Mask" "F.Paste")
			(net "GND")
		)
		(pad "274" smd rect
			(at 2.050034 51.425094 270)
			(size 0.519938 1.4986)
			(layers "F.Cu" "F.Mask" "F.Paste")
			(net "M_B_CPU0_SB_DQ<22>")
		)
	)
)
